FILE_TYPE = CONNECTIVITY;
{Allegro Design Entry HDL 17.4-2019 S026 (4007227) 1/17/2022}
"PAGE_NUMBER" = 49;
0"NC";
1"GMI_CPU0_G2_CPU1_G0_TX_DP<0:15>";
2"GMI_CPU0_G2_CPU1_G0_TX_DN<0:15>";
3"P5E_CPU1_G1_TX_DP<15:0>";
4"P5E_CPU1_G1_TX_DN<15:0>";
5"GMI_CPU1_G0_CPU0_G2_TX_DP<0:15>";
6"GMI_CPU1_G0_CPU0_G2_TX_DN<0:15>";
7"P5E_CPU1_G1_RX_DN<15:0>";
8"P5E_CPU1_G1_RX_DP<15:0>";
9"P5E_CPU1_G1_TX_DP<4>";
10"P5E_CPU1_G1_TX_DN<4>";
11"P5E_CPU1_G1_TX_DP<2>";
12"P5E_CPU1_G1_TX_DN<2>";
13"P5E_CPU1_G1_TX_DN<8>";
14"P5E_CPU1_G1_TX_DP<8>";
15"P5E_CPU1_G1_RX_DP<0>";
16"P5E_CPU1_G1_RX_DP<6>";
17"P5E_CPU1_G1_RX_DN<6>";
18"P5E_CPU1_G1_RX_DP<7>";
19"P5E_CPU1_G1_RX_DN<13>";
20"P5E_CPU1_G1_RX_DN<7>";
21"P5E_CPU1_G1_RX_DN<8>";
22"P5E_CPU1_G1_RX_DN<4>";
23"P5E_CPU1_G1_RX_DP<4>";
24"P5E_CPU1_G1_RX_DN<3>";
25"P5E_CPU1_G1_TX_DN<1>";
26"P5E_CPU1_G1_TX_DP<1>";
27"P5E_CPU1_G1_TX_DN<3>";
28"P5E_CPU1_G1_TX_DP<9>";
29"P5E_CPU1_G1_TX_DN<7>";
30"P5E_CPU1_G1_TX_DP<7>";
31"P5E_CPU1_G1_TX_DN<6>";
32"P5E_CPU1_G1_TX_DP<6>";
33"P5E_CPU1_G1_TX_DN<5>";
34"P5E_CPU1_G1_TX_DN<0>";
35"P5E_CPU1_G1_TX_DP<0>";
36"P5E_CPU1_G1_TX_DP<3>";
37"P5E_CPU1_G1_TX_DP<5>";
38"P5E_CPU1_G1_RX_DP<5>";
39"P5E_CPU1_G1_RX_DP<8>";
40"P5E_CPU1_G1_RX_DN<5>";
41"P5E_CPU1_G1_RX_DP<3>";
42"P5E_CPU1_G1_RX_DN<2>";
43"P5E_CPU1_G1_RX_DP<2>";
44"P5E_CPU1_G1_RX_DN<1>";
45"P5E_CPU1_G1_RX_DP<1>";
46"P5E_CPU1_G1_RX_DN<0>";
47"P5E_CPU1_G1_RX_DN<14>";
48"P5E_CPU1_G1_RX_DN<12>";
49"P5E_CPU1_G1_RX_DN<11>";
50"P5E_CPU1_G1_RX_DN<10>";
51"P5E_CPU1_G1_RX_DN<9>";
52"P5E_CPU1_G1_RX_DP<14>";
53"P5E_CPU1_G1_RX_DP<13>";
54"P5E_CPU1_G1_RX_DP<12>";
55"P5E_CPU1_G1_RX_DP<11>";
56"P5E_CPU1_G1_RX_DP<10>";
57"P5E_CPU1_G1_RX_DP<9>";
58"P5E_CPU1_G1_RX_DP<15>";
59"P5E_CPU1_G1_RX_DN<15>";
60"GMI_CPU1_G0_CPU0_G2_TX_DN<0>";
61"GMI_CPU1_G0_CPU0_G2_TX_DP<0>";
62"GMI_CPU1_G0_CPU0_G2_TX_DN<1>";
63"GMI_CPU1_G0_CPU0_G2_TX_DP<1>";
64"GMI_CPU1_G0_CPU0_G2_TX_DN<2>";
65"GMI_CPU1_G0_CPU0_G2_TX_DN<3>";
66"GMI_CPU1_G0_CPU0_G2_TX_DN<4>";
67"GMI_CPU1_G0_CPU0_G2_TX_DP<5>";
68"GMI_CPU1_G0_CPU0_G2_TX_DN<6>";
69"GMI_CPU1_G0_CPU0_G2_TX_DN<7>";
70"GMI_CPU1_G0_CPU0_G2_TX_DN<12>";
71"GMI_CPU1_G0_CPU0_G2_TX_DN<13>";
72"GMI_CPU1_G0_CPU0_G2_TX_DP<15>";
73"GMI_CPU1_G0_CPU0_G2_TX_DN<14>";
74"GMI_CPU1_G0_CPU0_G2_TX_DP<14>";
75"GMI_CPU0_G2_CPU1_G0_TX_DN<15>";
76"GMI_CPU0_G2_CPU1_G0_TX_DP<15>";
77"GMI_CPU0_G2_CPU1_G0_TX_DN<0>";
78"GMI_CPU1_G0_CPU0_G2_TX_DN<15>";
79"GMI_CPU1_G0_CPU0_G2_TX_DN<11>";
80"GMI_CPU1_G0_CPU0_G2_TX_DN<10>";
81"GMI_CPU1_G0_CPU0_G2_TX_DN<9>";
82"GMI_CPU1_G0_CPU0_G2_TX_DN<8>";
83"GMI_CPU1_G0_CPU0_G2_TX_DN<5>";
84"GMI_CPU1_G0_CPU0_G2_TX_DP<13>";
85"GMI_CPU1_G0_CPU0_G2_TX_DP<12>";
86"GMI_CPU1_G0_CPU0_G2_TX_DP<11>";
87"GMI_CPU1_G0_CPU0_G2_TX_DP<10>";
88"GMI_CPU1_G0_CPU0_G2_TX_DP<9>";
89"GMI_CPU1_G0_CPU0_G2_TX_DP<8>";
90"GMI_CPU1_G0_CPU0_G2_TX_DP<7>";
91"GMI_CPU1_G0_CPU0_G2_TX_DP<6>";
92"GMI_CPU1_G0_CPU0_G2_TX_DP<4>";
93"GMI_CPU1_G0_CPU0_G2_TX_DP<3>";
94"GMI_CPU1_G0_CPU0_G2_TX_DP<2>";
95"P5E_CPU1_G1_TX_DN<9>";
96"P5E_CPU1_G1_TX_DN<15>";
97"P5E_CPU1_G1_TX_DN<14>";
98"P5E_CPU1_G1_TX_DN<13>";
99"P5E_CPU1_G1_TX_DN<12>";
100"P5E_CPU1_G1_TX_DN<11>";
101"P5E_CPU1_G1_TX_DN<10>";
102"P5E_CPU1_G1_TX_DP<14>";
103"P5E_CPU1_G1_TX_DP<13>";
104"P5E_CPU1_G1_TX_DP<12>";
105"P5E_CPU1_G1_TX_DP<11>";
106"P5E_CPU1_G1_TX_DP<10>";
107"P5E_CPU1_G1_TX_DP<15>";
108"GMI_CPU0_G2_CPU1_G0_TX_DN<14>";
109"GMI_CPU0_G2_CPU1_G0_TX_DN<13>";
110"GMI_CPU0_G2_CPU1_G0_TX_DN<12>";
111"GMI_CPU0_G2_CPU1_G0_TX_DN<11>";
112"GMI_CPU0_G2_CPU1_G0_TX_DN<10>";
113"GMI_CPU0_G2_CPU1_G0_TX_DN<9>";
114"GMI_CPU0_G2_CPU1_G0_TX_DN<8>";
115"GMI_CPU0_G2_CPU1_G0_TX_DN<7>";
116"GMI_CPU0_G2_CPU1_G0_TX_DN<6>";
117"GMI_CPU0_G2_CPU1_G0_TX_DN<5>";
118"GMI_CPU0_G2_CPU1_G0_TX_DN<4>";
119"GMI_CPU0_G2_CPU1_G0_TX_DN<3>";
120"GMI_CPU0_G2_CPU1_G0_TX_DN<2>";
121"GMI_CPU0_G2_CPU1_G0_TX_DN<1>";
122"GMI_CPU0_G2_CPU1_G0_TX_DP<14>";
123"GMI_CPU0_G2_CPU1_G0_TX_DP<13>";
124"GMI_CPU0_G2_CPU1_G0_TX_DP<12>";
125"GMI_CPU0_G2_CPU1_G0_TX_DP<11>";
126"GMI_CPU0_G2_CPU1_G0_TX_DP<10>";
127"GMI_CPU0_G2_CPU1_G0_TX_DP<9>";
128"GMI_CPU0_G2_CPU1_G0_TX_DP<8>";
129"GMI_CPU0_G2_CPU1_G0_TX_DP<7>";
130"GMI_CPU0_G2_CPU1_G0_TX_DP<6>";
131"GMI_CPU0_G2_CPU1_G0_TX_DP<5>";
132"GMI_CPU0_G2_CPU1_G0_TX_DP<4>";
133"GMI_CPU0_G2_CPU1_G0_TX_DP<3>";
134"GMI_CPU0_G2_CPU1_G0_TX_DP<2>";
135"GMI_CPU0_G2_CPU1_G0_TX_DP<1>";
136"GMI_CPU0_G2_CPU1_G0_TX_DP<0>";
%"GENOA_SP5"
"11","(-4775,5000)","0","pure_quanta","I213";
;
LOCATION"U26"
$SEC"11"
CDS_SEC"11"
VALUE"SOCKET6096_13568-001"
MATERIAL"IO"
PART_TYPE"SMLF"
CDS_LMAN_SYM_OUTLINE"-1100,950,1100,-950"
NEEDS_NO_SIZE"TRUE"
CDS_LIB"pure_quanta"
PART_NUMBER"DGA^6000030";
"G0_TXP15"
$PN"AE52"61;
"G0_TXP14"
$PN"AC52"63;
"G0_TXP13"
$PN"AG52"94;
"G0_TXP12"
$PN"AE49"93;
"G0_TXP11"
$PN"AC49"92;
"G0_TXP10"
$PN"AG49"67;
"G0_TXP9"
$PN"AE46"91;
"G0_TXP8"
$PN"AC46"90;
"G0_TXP7"
$PN"AG46"89;
"G0_TXP6"
$PN"AE43"88;
"G0_TXP5"
$PN"AC43"87;
"G0_TXP4"
$PN"AA43"86;
"G0_TXP3"
$PN"AG43"85;
"G0_TXP2"
$PN"AB40"84;
"G0_TXP1"
$PN"AD40"74;
"G0_TXP0"
$PN"AF40"72;
"G0_TXN15"
$PN"AE53"60;
"G0_TXN14"
$PN"AC53"62;
"G0_TXN13"
$PN"AG53"64;
"G0_TXN12"
$PN"AE50"65;
"G0_TXN11"
$PN"AC50"66;
"G0_TXN10"
$PN"AG50"83;
"G0_TXN9"
$PN"AE47"68;
"G0_TXN8"
$PN"AC47"69;
"G0_TXN7"
$PN"AG47"82;
"G0_TXN6"
$PN"AE44"81;
"G0_TXN5"
$PN"AC44"80;
"G0_TXN4"
$PN"AA44"79;
"G0_TXN3"
$PN"AG44"70;
"G0_TXN2"
$PN"AB41"71;
"G0_TXN1"
$PN"AD41"73;
"G0_TXN0"
$PN"AF41"78;
"G0_RXP15"
$PN"N53"136;
"G0_RXP14"
$PN"J53"135;
"G0_RXP13"
$PN"G53"134;
"G0_RXP12"
$PN"L53"133;
"G0_RXP11"
$PN"J50"132;
"G0_RXP10"
$PN"G50"131;
"G0_RXP9"
$PN"L50"130;
"G0_RXP8"
$PN"J47"129;
"G0_RXP7"
$PN"G47"128;
"G0_RXP6"
$PN"L47"127;
"G0_RXP5"
$PN"J44"126;
"G0_RXP4"
$PN"G44"125;
"G0_RXP3"
$PN"L44"124;
"G0_RXP2"
$PN"H41"123;
"G0_RXP1"
$PN"K41"122;
"G0_RXP0"
$PN"M41"76;
"G0_RXN15"
$PN"N52"77;
"G0_RXN14"
$PN"J52"121;
"G0_RXN13"
$PN"G52"120;
"G0_RXN12"
$PN"L52"119;
"G0_RXN11"
$PN"J49"118;
"G0_RXN10"
$PN"G49"117;
"G0_RXN9"
$PN"L49"116;
"G0_RXN8"
$PN"J46"115;
"G0_RXN7"
$PN"G46"114;
"G0_RXN6"
$PN"L46"113;
"G0_RXN5"
$PN"J43"112;
"G0_RXN4"
$PN"G43"111;
"G0_RXN3"
$PN"L43"110;
"G0_RXN2"
$PN"H40"109;
"G0_RXN1"
$PN"K40"108;
"G0_RXN0"
$PN"M40"75;
%"GENOA_SP5"
"12","(-4750,2275)","0","pure_quanta","I214";
;
LOCATION"U26"
$SEC"12"
CDS_SEC"12"
MATERIAL"IO"
VALUE"SOCKET6096_13568-001"
PART_TYPE"SMLF"
CDS_LMAN_SYM_OUTLINE"-1100,950,1100,-950"
NEEDS_NO_SIZE"TRUE"
CDS_LIB"pure_quanta"
PART_NUMBER"DGA^6000030";
"G1_RXN7"
$PN"N46"20;
"G1_RXN6"
$PN"U46"17;
"G1_RXN5"
$PN"R43"40;
"G1_RXP7"
$PN"N47"18;
"G1_TXN7"
$PN"AN47"29;
"G1_RXN4"
$PN"N43"22;
"G1_RXP6"
$PN"U47"16;
"G1_TXN6"
$PN"AL44"31;
"G1_RXN3"
$PN"U43"24;
"G1_RXP5"
$PN"R44"38;
"G1_TXN5"
$PN"AJ44"33;
"G1_TXP7"
$PN"AN46"30;
"G1_RXN2"
$PN"P40"42;
"G1_RXP4"
$PN"N44"23;
"G1_TXN4"
$PN"AN44"10;
"G1_TXP6"
$PN"AL43"32;
"G1_RXN1"
$PN"T40"44;
"G1_RXP3"
$PN"U44"41;
"G1_TXN3"
$PN"AK41"27;
"G1_TXP5"
$PN"AJ43"37;
"G1_RXN0"
$PN"V40"46;
"G1_RXP2"
$PN"P41"43;
"G1_TXN2"
$PN"AH41"12;
"G1_TXP4"
$PN"AN43"9;
"G1_RXP1"
$PN"T41"45;
"G1_TXN1"
$PN"AM41"25;
"G1_TXP3"
$PN"AK40"36;
"G1_RXP0"
$PN"V41"15;
"G1_TXN0"
$PN"AP41"34;
"G1_TXP2"
$PN"AH40"11;
"G1_TXP1"
$PN"AM40"26;
"G1_TXP0"
$PN"AP40"35;
"G1_RXN8"
$PN"R46"21;
"G1_RXN9"
$PN"W49"51;
"G1_RXN10"
$PN"N49"50;
"G1_RXN11"
$PN"R49"49;
"G1_RXN12"
$PN"U49"48;
"G1_RXN13"
$PN"W52"19;
"G1_RXN14"
$PN"R52"47;
"G1_RXN15"
$PN"U52"59;
"G1_RXP8"
$PN"R47"39;
"G1_RXP9"
$PN"W50"57;
"G1_RXP10"
$PN"N50"56;
"G1_RXP11"
$PN"R50"55;
"G1_RXP12"
$PN"U50"54;
"G1_RXP13"
$PN"W53"53;
"G1_RXP14"
$PN"R53"52;
"G1_RXP15"
$PN"U53"58;
"G1_TXN8"
$PN"AJ47"13;
"G1_TXN9"
$PN"AL47"95;
"G1_TXN10"
$PN"AN50"101;
"G1_TXN11"
$PN"AJ50"100;
"G1_TXN12"
$PN"AL50"99;
"G1_TXN13"
$PN"AN53"98;
"G1_TXN14"
$PN"AJ53"97;
"G1_TXN15"
$PN"AL53"96;
"G1_TXP8"
$PN"AJ46"14;
"G1_TXP9"
$PN"AL46"28;
"G1_TXP10"
$PN"AN49"106;
"G1_TXP11"
$PN"AJ49"105;
"G1_TXP12"
$PN"AL49"104;
"G1_TXP13"
$PN"AN52"103;
"G1_TXP14"
$PN"AJ52"102;
"G1_TXP15"
$PN"AL52"107;
%"TAP"
"6","(-3100,5650)","2","mstr_standard","I235";
;
ROOM"RISER1"
CDS_LIB"mstr_standard"
BOM_COST"IO_SLOT"
BODY_TYPE"PLUMBING"
HDL_TAP"TRUE";
"B \NAC \NWC"5;
"S \NAC"
BN"14"74;
%"TAP"
"6","(-3100,5750)","2","mstr_standard","I236";
;
ROOM"RISER1"
CDS_LIB"mstr_standard"
BOM_COST"IO_SLOT"
BODY_TYPE"PLUMBING"
HDL_TAP"TRUE";
"B \NAC \NWC"5;
"S \NAC"
BN"15"72;
%"TAP"
"6","(-3100,5550)","2","standard","I240";
;
ROOM"RISER1"
CDS_LIB"standard"
BOM_COST"IO_SLOT"
BODY_TYPE"PLUMBING"
HDL_TAP"TRUE";
"B \NAC \NWC"5;
"S \NAC"
BN"13"84;
%"TAP"
"6","(-3100,5450)","2","standard","I241";
;
ROOM"RISER1"
CDS_LIB"standard"
BOM_COST"IO_SLOT"
BODY_TYPE"PLUMBING"
HDL_TAP"TRUE";
"B \NAC \NWC"5;
"S \NAC"
BN"12"85;
%"TAP"
"6","(-3100,5350)","2","standard","I244";
;
ROOM"RISER1"
CDS_LIB"standard"
BOM_COST"IO_SLOT"
BODY_TYPE"PLUMBING"
HDL_TAP"TRUE";
"B \NAC \NWC"5;
"S \NAC"
BN"11"86;
%"TAP"
"6","(-3100,5250)","2","standard","I245";
;
ROOM"RISER1"
CDS_LIB"standard"
BOM_COST"IO_SLOT"
BODY_TYPE"PLUMBING"
HDL_TAP"TRUE";
"B \NAC \NWC"5;
"S \NAC"
BN"10"87;
%"TAP"
"6","(-3100,5150)","2","standard","I246";
;
ROOM"RISER1"
CDS_LIB"standard"
BOM_COST"IO_SLOT"
BODY_TYPE"PLUMBING"
HDL_TAP"TRUE";
"B \NAC \NWC"5;
"S \NAC"
BN"9"88;
%"TAP"
"6","(-3100,5050)","2","standard","I250";
;
ROOM"RISER1"
CDS_LIB"standard"
BOM_COST"IO_SLOT"
BODY_TYPE"PLUMBING"
HDL_TAP"TRUE";
"B \NAC \NWC"5;
"S \NAC"
BN"8"89;
%"TAP"
"6","(-3100,4950)","2","standard","I251";
;
ROOM"RISER1"
CDS_LIB"standard"
BOM_COST"IO_SLOT"
BODY_TYPE"PLUMBING"
HDL_TAP"TRUE";
"B \NAC \NWC"5;
"S \NAC"
BN"7"90;
%"TAP"
"6","(-3100,4850)","2","standard","I254";
;
ROOM"RISER1"
CDS_LIB"standard"
BOM_COST"IO_SLOT"
BODY_TYPE"PLUMBING"
HDL_TAP"TRUE";
"B \NAC \NWC"5;
"S \NAC"
BN"6"91;
%"TAP"
"6","(-3100,4750)","2","standard","I255";
;
ROOM"RISER1"
CDS_LIB"standard"
BOM_COST"IO_SLOT"
BODY_TYPE"PLUMBING"
HDL_TAP"TRUE";
"B \NAC \NWC"5;
"S \NAC"
BN"5"67;
%"TAP"
"6","(-3100,4650)","2","standard","I256";
;
ROOM"RISER1"
CDS_LIB"standard"
BOM_COST"IO_SLOT"
BODY_TYPE"PLUMBING"
HDL_TAP"TRUE";
"B \NAC \NWC"5;
"S \NAC"
BN"4"92;
%"TAP"
"6","(-3100,4550)","2","standard","I260";
;
ROOM"RISER1"
CDS_LIB"standard"
BOM_COST"IO_SLOT"
BODY_TYPE"PLUMBING"
HDL_TAP"TRUE";
"B \NAC \NWC"5;
"S \NAC"
BN"3"93;
%"TAP"
"6","(-3100,4450)","2","standard","I261";
;
ROOM"RISER1"
CDS_LIB"standard"
BOM_COST"IO_SLOT"
BODY_TYPE"PLUMBING"
HDL_TAP"TRUE";
"B \NAC \NWC"5;
"S \NAC"
BN"2"94;
%"TAP"
"6","(-3100,4350)","2","standard","I264";
;
ROOM"RISER1"
CDS_LIB"standard"
BOM_COST"IO_SLOT"
BODY_TYPE"PLUMBING"
HDL_TAP"TRUE";
"B \NAC \NWC"5;
"S \NAC"
BN"1"63;
%"TAP"
"6","(-3100,4250)","2","standard","I265";
;
ROOM"RISER1"
CDS_LIB"standard"
BOM_COST"IO_SLOT"
BODY_TYPE"PLUMBING"
HDL_TAP"TRUE";
"B \NAC \NWC"5;
"S \NAC"
BN"0"61;
%"TAP"
"6","(-3075,2925)","2","mstr_standard","I270";
;
ROOM"RISER1"
BOM_COST"IO_SLOT"
CDS_LIB"mstr_standard"
BODY_TYPE"PLUMBING"
HDL_TAP"TRUE";
"B \NAC \NWC"3;
"S \NAC"
BN"1"26;
%"TAP"
"6","(-3075,2825)","2","standard","I271";
;
ROOM"RISER1"
BOM_COST"IO_SLOT"
CDS_LIB"standard"
BODY_TYPE"PLUMBING"
HDL_TAP"TRUE";
"B \NAC \NWC"3;
"S \NAC"
BN"2"11;
%"TAP"
"6","(-3075,3025)","2","mstr_standard","I272";
;
ROOM"RISER1"
BOM_COST"IO_SLOT"
CDS_LIB"mstr_standard"
BODY_TYPE"PLUMBING"
HDL_TAP"TRUE";
"B \NAC \NWC"3;
"S \NAC"
BN"0"35;
%"TAP"
"6","(-3075,2725)","2","standard","I276";
;
ROOM"RISER1"
BOM_COST"IO_SLOT"
CDS_LIB"standard"
BODY_TYPE"PLUMBING"
HDL_TAP"TRUE";
"B \NAC \NWC"3;
"S \NAC"
BN"3"36;
%"TAP"
"6","(-3075,2625)","2","standard","I277";
;
ROOM"RISER1"
BOM_COST"IO_SLOT"
CDS_LIB"standard"
BODY_TYPE"PLUMBING"
HDL_TAP"TRUE";
"B \NAC \NWC"3;
"S \NAC"
BN"4"9;
%"TAP"
"6","(-3075,2425)","2","standard","I280";
;
ROOM"RISER1"
BOM_COST"IO_SLOT"
CDS_LIB"standard"
BODY_TYPE"PLUMBING"
HDL_TAP"TRUE";
"B \NAC \NWC"3;
"S \NAC"
BN"6"32;
%"TAP"
"6","(-3075,2325)","2","standard","I281";
;
ROOM"RISER1"
BOM_COST"IO_SLOT"
CDS_LIB"standard"
BODY_TYPE"PLUMBING"
HDL_TAP"TRUE";
"B \NAC \NWC"3;
"S \NAC"
BN"7"30;
%"TAP"
"6","(-3075,2525)","2","standard","I282";
;
ROOM"RISER1"
BOM_COST"IO_SLOT"
CDS_LIB"standard"
BODY_TYPE"PLUMBING"
HDL_TAP"TRUE";
"B \NAC \NWC"3;
"S \NAC"
BN"5"37;
%"TAP"
"6","(-3075,2225)","2","standard","I286";
;
ROOM"RISER1"
BOM_COST"IO_SLOT"
CDS_LIB"standard"
BODY_TYPE"PLUMBING"
HDL_TAP"TRUE";
"B \NAC \NWC"3;
"S \NAC"
BN"8"14;
%"TAP"
"6","(-3075,2125)","2","standard","I287";
;
ROOM"RISER1"
BOM_COST"IO_SLOT"
CDS_LIB"standard"
BODY_TYPE"PLUMBING"
HDL_TAP"TRUE";
"B \NAC \NWC"3;
"S \NAC"
BN"9"28;
%"TAP"
"6","(-3075,1925)","2","standard","I290";
;
ROOM"RISER1"
BOM_COST"IO_SLOT"
CDS_LIB"standard"
BODY_TYPE"PLUMBING"
HDL_TAP"TRUE";
"B \NAC \NWC"3;
"S \NAC"
BN"11"105;
%"TAP"
"6","(-3075,1825)","2","standard","I291";
;
ROOM"RISER1"
BOM_COST"IO_SLOT"
CDS_LIB"standard"
BODY_TYPE"PLUMBING"
HDL_TAP"TRUE";
"B \NAC \NWC"3;
"S \NAC"
BN"12"104;
%"TAP"
"6","(-3075,2025)","2","standard","I292";
;
ROOM"RISER1"
BOM_COST"IO_SLOT"
CDS_LIB"standard"
BODY_TYPE"PLUMBING"
HDL_TAP"TRUE";
"B \NAC \NWC"3;
"S \NAC"
BN"10"106;
%"TAP"
"6","(-3075,1725)","2","standard","I296";
;
ROOM"RISER1"
BOM_COST"IO_SLOT"
CDS_LIB"standard"
BODY_TYPE"PLUMBING"
HDL_TAP"TRUE";
"B \NAC \NWC"3;
"S \NAC"
BN"13"103;
%"TAP"
"6","(-3075,1625)","2","standard","I297";
;
ROOM"RISER1"
BOM_COST"IO_SLOT"
CDS_LIB"standard"
BODY_TYPE"PLUMBING"
HDL_TAP"TRUE";
"B \NAC \NWC"3;
"S \NAC"
BN"14"102;
%"TAP"
"6","(-3075,1525)","2","standard","I298";
;
ROOM"RISER1"
BOM_COST"IO_SLOT"
CDS_LIB"standard"
BODY_TYPE"PLUMBING"
HDL_TAP"TRUE";
"B \NAC \NWC"3;
"S \NAC"
BN"15"107;
%"TAP"
"6","(-6525,5750)","0","mstr_standard","I300";
;
CDS_LIB"mstr_standard"
BODY_TYPE"PLUMBING"
HDL_TAP"TRUE";
"B \NAC \NWC"1;
"S \NAC"
BN"15"76;
%"TAP"
"6","(-6525,5650)","0","mstr_standard","I301";
;
CDS_LIB"mstr_standard"
BODY_TYPE"PLUMBING"
HDL_TAP"TRUE";
"B \NAC \NWC"1;
"S \NAC"
BN"14"122;
%"TAP"
"6","(-6525,5550)","0","mstr_standard","I303";
;
CDS_LIB"mstr_standard"
BODY_TYPE"PLUMBING"
HDL_TAP"TRUE";
"B \NAC \NWC"1;
"S \NAC"
BN"13"123;
%"TAP"
"6","(-6525,5450)","0","standard","I304";
;
CDS_LIB"standard"
BODY_TYPE"PLUMBING"
HDL_TAP"TRUE";
"B \NAC \NWC"1;
"S \NAC"
BN"12"124;
%"TAP"
"6","(-6525,5250)","0","standard","I308";
;
CDS_LIB"standard"
BODY_TYPE"PLUMBING"
HDL_TAP"TRUE";
"B \NAC \NWC"1;
"S \NAC"
BN"10"126;
%"TAP"
"6","(-6525,5350)","0","standard","I309";
;
CDS_LIB"standard"
BODY_TYPE"PLUMBING"
HDL_TAP"TRUE";
"B \NAC \NWC"1;
"S \NAC"
BN"11"125;
%"TAP"
"6","(-6525,5150)","0","standard","I310";
;
CDS_LIB"standard"
BODY_TYPE"PLUMBING"
HDL_TAP"TRUE";
"B \NAC \NWC"1;
"S \NAC"
BN"9"127;
%"TAP"
"6","(-6525,5050)","0","standard","I313";
;
CDS_LIB"standard"
BODY_TYPE"PLUMBING"
HDL_TAP"TRUE";
"B \NAC \NWC"1;
"S \NAC"
BN"8"128;
%"TAP"
"6","(-6525,4950)","0","standard","I314";
;
CDS_LIB"standard"
BODY_TYPE"PLUMBING"
HDL_TAP"TRUE";
"B \NAC \NWC"1;
"S \NAC"
BN"7"129;
%"TAP"
"6","(-6525,4850)","0","standard","I318";
;
CDS_LIB"standard"
BODY_TYPE"PLUMBING"
HDL_TAP"TRUE";
"B \NAC \NWC"1;
"S \NAC"
BN"6"130;
%"TAP"
"6","(-6525,4750)","0","standard","I319";
;
CDS_LIB"standard"
BODY_TYPE"PLUMBING"
HDL_TAP"TRUE";
"B \NAC \NWC"1;
"S \NAC"
BN"5"131;
%"TAP"
"6","(-6525,4650)","0","standard","I320";
;
CDS_LIB"standard"
BODY_TYPE"PLUMBING"
HDL_TAP"TRUE";
"B \NAC \NWC"1;
"S \NAC"
BN"4"132;
%"TAP"
"6","(-6525,4550)","0","standard","I323";
;
CDS_LIB"standard"
BODY_TYPE"PLUMBING"
HDL_TAP"TRUE";
"B \NAC \NWC"1;
"S \NAC"
BN"3"133;
%"TAP"
"6","(-6525,4450)","0","standard","I324";
;
CDS_LIB"standard"
BODY_TYPE"PLUMBING"
HDL_TAP"TRUE";
"B \NAC \NWC"1;
"S \NAC"
BN"2"134;
%"TAP"
"6","(-6525,4250)","0","standard","I328";
;
CDS_LIB"standard"
BODY_TYPE"PLUMBING"
HDL_TAP"TRUE";
"B \NAC \NWC"1;
"S \NAC"
BN"0"136;
%"TAP"
"6","(-6525,4350)","0","standard","I329";
;
CDS_LIB"standard"
BODY_TYPE"PLUMBING"
HDL_TAP"TRUE";
"B \NAC \NWC"1;
"S \NAC"
BN"1"135;
%"TAP"
"6","(-6500,3025)","0","mstr_standard","I334";
;
CDS_LIB"mstr_standard"
BODY_TYPE"PLUMBING"
HDL_TAP"TRUE";
"B \NAC \NWC"8;
"S \NAC"
BN"0"15;
%"TAP"
"6","(-6500,2925)","0","mstr_standard","I335";
;
CDS_LIB"mstr_standard"
BODY_TYPE"PLUMBING"
HDL_TAP"TRUE";
"B \NAC \NWC"8;
"S \NAC"
BN"1"45;
%"TAP"
"6","(-6500,2825)","0","mstr_standard","I336";
;
CDS_LIB"mstr_standard"
BODY_TYPE"PLUMBING"
HDL_TAP"TRUE";
"B \NAC \NWC"8;
"S \NAC"
BN"2"43;
%"TAP"
"6","(-6500,2725)","0","standard","I339";
;
CDS_LIB"standard"
BODY_TYPE"PLUMBING"
HDL_TAP"TRUE";
"B \NAC \NWC"8;
"S \NAC"
BN"3"41;
%"TAP"
"6","(-6500,2625)","0","standard","I340";
;
CDS_LIB"standard"
BODY_TYPE"PLUMBING"
HDL_TAP"TRUE";
"B \NAC \NWC"8;
"S \NAC"
BN"4"23;
%"TAP"
"6","(-6500,2525)","0","standard","I344";
;
CDS_LIB"standard"
BODY_TYPE"PLUMBING"
HDL_TAP"TRUE";
"B \NAC \NWC"8;
"S \NAC"
BN"5"38;
%"TAP"
"6","(-6500,2425)","0","standard","I345";
;
CDS_LIB"standard"
BODY_TYPE"PLUMBING"
HDL_TAP"TRUE";
"B \NAC \NWC"8;
"S \NAC"
BN"6"16;
%"TAP"
"6","(-6500,2325)","0","standard","I346";
;
CDS_LIB"standard"
BODY_TYPE"PLUMBING"
HDL_TAP"TRUE";
"B \NAC \NWC"8;
"S \NAC"
BN"7"18;
%"TAP"
"6","(-6500,2225)","0","standard","I349";
;
CDS_LIB"standard"
BODY_TYPE"PLUMBING"
HDL_TAP"TRUE";
"B \NAC \NWC"8;
"S \NAC"
BN"8"39;
%"TAP"
"6","(-6500,2125)","0","standard","I350";
;
CDS_LIB"standard"
BODY_TYPE"PLUMBING"
HDL_TAP"TRUE";
"B \NAC \NWC"8;
"S \NAC"
BN"9"57;
%"TAP"
"6","(-6500,2025)","0","standard","I356";
;
CDS_LIB"standard"
BODY_TYPE"PLUMBING"
HDL_TAP"TRUE";
"B \NAC \NWC"8;
"S \NAC"
BN"10"56;
%"TAP"
"6","(-6500,1925)","0","standard","I357";
;
CDS_LIB"standard"
BODY_TYPE"PLUMBING"
HDL_TAP"TRUE";
"B \NAC \NWC"8;
"S \NAC"
BN"11"55;
%"TAP"
"6","(-6500,1825)","0","standard","I358";
;
CDS_LIB"standard"
BODY_TYPE"PLUMBING"
HDL_TAP"TRUE";
"B \NAC \NWC"8;
"S \NAC"
BN"12"54;
%"TAP"
"6","(-6500,1725)","0","standard","I361";
;
CDS_LIB"standard"
BODY_TYPE"PLUMBING"
HDL_TAP"TRUE";
"B \NAC \NWC"8;
"S \NAC"
BN"13"53;
%"TAP"
"6","(-6500,1625)","0","standard","I362";
;
CDS_LIB"standard"
BODY_TYPE"PLUMBING"
HDL_TAP"TRUE";
"B \NAC \NWC"8;
"S \NAC"
BN"14"52;
%"TAP"
"6","(-6500,1525)","0","standard","I366";
;
CDS_LIB"standard"
BODY_TYPE"PLUMBING"
HDL_TAP"TRUE";
"B \NAC \NWC"8;
"S \NAC"
BN"15"58;
%"TAP"
"6","(-2950,5700)","2","mstr_standard","I437";
;
ROOM"RISER1"
BOM_COST"IO_SLOT"
CDS_LIB"mstr_standard"
BODY_TYPE"PLUMBING"
HDL_TAP"TRUE";
"B \NAC \NWC"6;
"S \NAC"
BN"15"78;
%"TAP"
"6","(-2950,5600)","2","mstr_standard","I438";
;
ROOM"RISER1"
CDS_LIB"mstr_standard"
BOM_COST"IO_SLOT"
BODY_TYPE"PLUMBING"
HDL_TAP"TRUE";
"B \NAC \NWC"6;
"S \NAC"
BN"14"73;
%"TAP"
"6","(-2950,5500)","2","standard","I439";
;
ROOM"RISER1"
CDS_LIB"standard"
BOM_COST"IO_SLOT"
BODY_TYPE"PLUMBING"
HDL_TAP"TRUE";
"B \NAC \NWC"6;
"S \NAC"
BN"13"71;
%"TAP"
"6","(-2950,5400)","2","standard","I440";
;
ROOM"RISER1"
CDS_LIB"standard"
BOM_COST"IO_SLOT"
BODY_TYPE"PLUMBING"
HDL_TAP"TRUE";
"B \NAC \NWC"6;
"S \NAC"
BN"12"70;
%"TAP"
"6","(-2950,5300)","2","standard","I441";
;
ROOM"RISER1"
CDS_LIB"standard"
BOM_COST"IO_SLOT"
BODY_TYPE"PLUMBING"
HDL_TAP"TRUE";
"B \NAC \NWC"6;
"S \NAC"
BN"11"79;
%"TAP"
"6","(-2950,5200)","2","standard","I442";
;
ROOM"RISER1"
CDS_LIB"standard"
BOM_COST"IO_SLOT"
BODY_TYPE"PLUMBING"
HDL_TAP"TRUE";
"B \NAC \NWC"6;
"S \NAC"
BN"10"80;
%"TAP"
"6","(-2950,5100)","2","standard","I443";
;
ROOM"RISER1"
CDS_LIB"standard"
BOM_COST"IO_SLOT"
BODY_TYPE"PLUMBING"
HDL_TAP"TRUE";
"B \NAC \NWC"6;
"S \NAC"
BN"9"81;
%"TAP"
"6","(-2950,5000)","2","standard","I444";
;
ROOM"RISER1"
CDS_LIB"standard"
BOM_COST"IO_SLOT"
BODY_TYPE"PLUMBING"
HDL_TAP"TRUE";
"B \NAC \NWC"6;
"S \NAC"
BN"8"82;
%"TAP"
"6","(-2950,4900)","2","standard","I445";
;
ROOM"RISER1"
CDS_LIB"standard"
BOM_COST"IO_SLOT"
BODY_TYPE"PLUMBING"
HDL_TAP"TRUE";
"B \NAC \NWC"6;
"S \NAC"
BN"7"69;
%"TAP"
"6","(-2950,4700)","2","standard","I446";
;
ROOM"RISER1"
CDS_LIB"standard"
BOM_COST"IO_SLOT"
BODY_TYPE"PLUMBING"
HDL_TAP"TRUE";
"B \NAC \NWC"6;
"S \NAC"
BN"5"83;
%"TAP"
"6","(-2950,4800)","2","standard","I447";
;
ROOM"RISER1"
CDS_LIB"standard"
BOM_COST"IO_SLOT"
BODY_TYPE"PLUMBING"
HDL_TAP"TRUE";
"B \NAC \NWC"6;
"S \NAC"
BN"6"68;
%"TAP"
"6","(-2950,4600)","2","standard","I448";
;
ROOM"RISER1"
CDS_LIB"standard"
BOM_COST"IO_SLOT"
BODY_TYPE"PLUMBING"
HDL_TAP"TRUE";
"B \NAC \NWC"6;
"S \NAC"
BN"4"66;
%"TAP"
"6","(-2950,4500)","2","standard","I449";
;
ROOM"RISER1"
CDS_LIB"standard"
BOM_COST"IO_SLOT"
BODY_TYPE"PLUMBING"
HDL_TAP"TRUE";
"B \NAC \NWC"6;
"S \NAC"
BN"3"65;
%"TAP"
"6","(-2950,4300)","2","standard","I450";
;
ROOM"RISER1"
BOM_COST"IO_SLOT"
CDS_LIB"standard"
BODY_TYPE"PLUMBING"
HDL_TAP"TRUE";
"B \NAC \NWC"6;
"S \NAC"
BN"1"62;
%"TAP"
"6","(-2950,4400)","2","standard","I451";
;
ROOM"RISER1"
CDS_LIB"standard"
BOM_COST"IO_SLOT"
BODY_TYPE"PLUMBING"
HDL_TAP"TRUE";
"B \NAC \NWC"6;
"S \NAC"
BN"2"64;
%"TAP"
"6","(-2950,4200)","2","standard","I452";
;
ROOM"RISER1"
CDS_LIB"standard"
BOM_COST"IO_SLOT"
BODY_TYPE"PLUMBING"
HDL_TAP"TRUE";
"B \NAC \NWC"6;
"S \NAC"
BN"0"60;
%"TAP"
"6","(-6675,5700)","0","mstr_standard","I453";
;
CDS_LIB"mstr_standard"
BODY_TYPE"PLUMBING"
HDL_TAP"TRUE";
"B \NAC \NWC"2;
"S \NAC"
BN"15"75;
%"TAP"
"6","(-6675,5600)","0","mstr_standard","I454";
;
CDS_LIB"mstr_standard"
BODY_TYPE"PLUMBING"
HDL_TAP"TRUE";
"B \NAC \NWC"2;
"S \NAC"
BN"14"108;
%"TAP"
"6","(-6675,5500)","0","standard","I455";
;
CDS_LIB"standard"
BODY_TYPE"PLUMBING"
HDL_TAP"TRUE";
"B \NAC \NWC"2;
"S \NAC"
BN"13"109;
%"TAP"
"6","(-6675,5400)","0","standard","I456";
;
CDS_LIB"standard"
BODY_TYPE"PLUMBING"
HDL_TAP"TRUE";
"B \NAC \NWC"2;
"S \NAC"
BN"12"110;
%"TAP"
"6","(-6675,5200)","0","standard","I457";
;
CDS_LIB"standard"
BODY_TYPE"PLUMBING"
HDL_TAP"TRUE";
"B \NAC \NWC"2;
"S \NAC"
BN"10"112;
%"TAP"
"6","(-6675,5300)","0","standard","I458";
;
CDS_LIB"standard"
BODY_TYPE"PLUMBING"
HDL_TAP"TRUE";
"B \NAC \NWC"2;
"S \NAC"
BN"11"111;
%"TAP"
"6","(-6675,5100)","0","standard","I459";
;
CDS_LIB"standard"
BODY_TYPE"PLUMBING"
HDL_TAP"TRUE";
"B \NAC \NWC"2;
"S \NAC"
BN"9"113;
%"TAP"
"6","(-6675,5000)","0","standard","I460";
;
CDS_LIB"standard"
BODY_TYPE"PLUMBING"
HDL_TAP"TRUE";
"B \NAC \NWC"2;
"S \NAC"
BN"8"114;
%"TAP"
"6","(-6675,4900)","0","standard","I461";
;
CDS_LIB"standard"
BODY_TYPE"PLUMBING"
HDL_TAP"TRUE";
"B \NAC \NWC"2;
"S \NAC"
BN"7"115;
%"TAP"
"6","(-6675,4800)","0","standard","I462";
;
CDS_LIB"standard"
BODY_TYPE"PLUMBING"
HDL_TAP"TRUE";
"B \NAC \NWC"2;
"S \NAC"
BN"6"116;
%"TAP"
"6","(-6675,4700)","0","standard","I463";
;
CDS_LIB"standard"
BODY_TYPE"PLUMBING"
HDL_TAP"TRUE";
"B \NAC \NWC"2;
"S \NAC"
BN"5"117;
%"TAP"
"6","(-6675,4600)","0","standard","I464";
;
CDS_LIB"standard"
BODY_TYPE"PLUMBING"
HDL_TAP"TRUE";
"B \NAC \NWC"2;
"S \NAC"
BN"4"118;
%"TAP"
"6","(-6675,4500)","0","standard","I465";
;
CDS_LIB"standard"
BODY_TYPE"PLUMBING"
HDL_TAP"TRUE";
"B \NAC \NWC"2;
"S \NAC"
BN"3"119;
%"TAP"
"6","(-6675,4400)","0","standard","I466";
;
CDS_LIB"standard"
BODY_TYPE"PLUMBING"
HDL_TAP"TRUE";
"B \NAC \NWC"2;
"S \NAC"
BN"2"120;
%"TAP"
"6","(-6675,4200)","0","standard","I467";
;
CDS_LIB"standard"
BODY_TYPE"PLUMBING"
HDL_TAP"TRUE";
"B \NAC \NWC"2;
"S \NAC"
BN"0"77;
%"TAP"
"6","(-6675,4300)","0","standard","I468";
;
CDS_LIB"standard"
BODY_TYPE"PLUMBING"
HDL_TAP"TRUE";
"B \NAC \NWC"2;
"S \NAC"
BN"1"121;
%"TAP"
"6","(-6650,2875)","0","mstr_standard","I470";
;
CDS_LIB"mstr_standard"
BODY_TYPE"PLUMBING"
HDL_TAP"TRUE";
"B \NAC \NWC"7;
"S \NAC"
BN"1"44;
%"TAP"
"6","(-6650,2975)","0","mstr_standard","I471";
;
CDS_LIB"mstr_standard"
BODY_TYPE"PLUMBING"
HDL_TAP"TRUE";
"B \NAC \NWC"7;
"S \NAC"
BN"0"46;
%"TAP"
"6","(-6650,2775)","0","standard","I472";
;
CDS_LIB"standard"
BODY_TYPE"PLUMBING"
HDL_TAP"TRUE";
"B \NAC \NWC"7;
"S \NAC"
BN"2"42;
%"TAP"
"6","(-6650,2675)","0","standard","I473";
;
CDS_LIB"standard"
BODY_TYPE"PLUMBING"
HDL_TAP"TRUE";
"B \NAC \NWC"7;
"S \NAC"
BN"3"24;
%"TAP"
"6","(-6650,2475)","0","standard","I474";
;
CDS_LIB"standard"
BODY_TYPE"PLUMBING"
HDL_TAP"TRUE";
"B \NAC \NWC"7;
"S \NAC"
BN"5"40;
%"TAP"
"6","(-6650,2575)","0","standard","I475";
;
CDS_LIB"standard"
BODY_TYPE"PLUMBING"
HDL_TAP"TRUE";
"B \NAC \NWC"7;
"S \NAC"
BN"4"22;
%"TAP"
"6","(-6650,2375)","0","standard","I476";
;
CDS_LIB"standard"
BODY_TYPE"PLUMBING"
HDL_TAP"TRUE";
"B \NAC \NWC"7;
"S \NAC"
BN"6"17;
%"TAP"
"6","(-6650,2275)","0","standard","I477";
;
CDS_LIB"standard"
BODY_TYPE"PLUMBING"
HDL_TAP"TRUE";
"B \NAC \NWC"7;
"S \NAC"
BN"7"20;
%"TAP"
"6","(-6650,2175)","0","standard","I478";
;
CDS_LIB"standard"
BODY_TYPE"PLUMBING"
HDL_TAP"TRUE";
"B \NAC \NWC"7;
"S \NAC"
BN"8"21;
%"TAP"
"6","(-6650,1975)","0","standard","I479";
;
CDS_LIB"standard"
BODY_TYPE"PLUMBING"
HDL_TAP"TRUE";
"B \NAC \NWC"7;
"S \NAC"
BN"10"50;
%"TAP"
"6","(-6650,2075)","0","standard","I480";
;
CDS_LIB"standard"
BODY_TYPE"PLUMBING"
HDL_TAP"TRUE";
"B \NAC \NWC"7;
"S \NAC"
BN"9"51;
%"TAP"
"6","(-6650,1875)","0","standard","I481";
;
CDS_LIB"standard"
BODY_TYPE"PLUMBING"
HDL_TAP"TRUE";
"B \NAC \NWC"7;
"S \NAC"
BN"11"49;
%"TAP"
"6","(-6650,1775)","0","standard","I482";
;
CDS_LIB"standard"
BODY_TYPE"PLUMBING"
HDL_TAP"TRUE";
"B \NAC \NWC"7;
"S \NAC"
BN"12"48;
%"TAP"
"6","(-6650,1675)","0","standard","I483";
;
CDS_LIB"standard"
BODY_TYPE"PLUMBING"
HDL_TAP"TRUE";
"B \NAC \NWC"7;
"S \NAC"
BN"13"19;
%"TAP"
"6","(-6650,1575)","0","standard","I484";
;
CDS_LIB"standard"
BODY_TYPE"PLUMBING"
HDL_TAP"TRUE";
"B \NAC \NWC"7;
"S \NAC"
BN"14"47;
%"TAP"
"6","(-6650,1475)","0","standard","I485";
;
CDS_LIB"standard"
BODY_TYPE"PLUMBING"
HDL_TAP"TRUE";
"B \NAC \NWC"7;
"S \NAC"
BN"15"59;
%"TAP"
"6","(-2925,2975)","2","mstr_standard","I488";
;
ROOM"RISER1"
CDS_LIB"mstr_standard"
BOM_COST"IO_SLOT"
BODY_TYPE"PLUMBING"
HDL_TAP"TRUE";
"B \NAC \NWC"4;
"S \NAC"
BN"0"34;
%"TAP"
"6","(-2925,2875)","2","mstr_standard","I489";
;
ROOM"RISER1"
BOM_COST"IO_SLOT"
CDS_LIB"mstr_standard"
BODY_TYPE"PLUMBING"
HDL_TAP"TRUE";
"B \NAC \NWC"4;
"S \NAC"
BN"1"25;
%"TAP"
"6","(-2925,2775)","2","standard","I490";
;
ROOM"RISER1"
BOM_COST"IO_SLOT"
CDS_LIB"standard"
BODY_TYPE"PLUMBING"
HDL_TAP"TRUE";
"B \NAC \NWC"4;
"S \NAC"
BN"2"12;
%"TAP"
"6","(-2925,2675)","2","standard","I491";
;
ROOM"RISER1"
BOM_COST"IO_SLOT"
CDS_LIB"standard"
BODY_TYPE"PLUMBING"
HDL_TAP"TRUE";
"B \NAC \NWC"4;
"S \NAC"
BN"3"27;
%"TAP"
"6","(-2925,2575)","2","standard","I492";
;
ROOM"RISER1"
BOM_COST"IO_SLOT"
CDS_LIB"standard"
BODY_TYPE"PLUMBING"
HDL_TAP"TRUE";
"B \NAC \NWC"4;
"S \NAC"
BN"4"10;
%"TAP"
"6","(-2925,2475)","2","standard","I493";
;
ROOM"RISER1"
BOM_COST"IO_SLOT"
CDS_LIB"standard"
BODY_TYPE"PLUMBING"
HDL_TAP"TRUE";
"B \NAC \NWC"4;
"S \NAC"
BN"5"33;
%"TAP"
"6","(-2925,2375)","2","standard","I494";
;
ROOM"RISER1"
BOM_COST"IO_SLOT"
CDS_LIB"standard"
BODY_TYPE"PLUMBING"
HDL_TAP"TRUE";
"B \NAC \NWC"4;
"S \NAC"
BN"6"31;
%"TAP"
"6","(-2925,2275)","2","standard","I495";
;
ROOM"RISER1"
BOM_COST"IO_SLOT"
CDS_LIB"standard"
BODY_TYPE"PLUMBING"
HDL_TAP"TRUE";
"B \NAC \NWC"4;
"S \NAC"
BN"7"29;
%"TAP"
"6","(-2925,2175)","2","standard","I496";
;
ROOM"RISER1"
BOM_COST"IO_SLOT"
CDS_LIB"standard"
BODY_TYPE"PLUMBING"
HDL_TAP"TRUE";
"B \NAC \NWC"4;
"S \NAC"
BN"8"13;
%"TAP"
"6","(-2925,1975)","2","standard","I497";
;
ROOM"RISER1"
BOM_COST"IO_SLOT"
CDS_LIB"standard"
BODY_TYPE"PLUMBING"
HDL_TAP"TRUE";
"B \NAC \NWC"4;
"S \NAC"
BN"10"101;
%"TAP"
"6","(-2925,2075)","2","standard","I498";
;
ROOM"RISER1"
BOM_COST"IO_SLOT"
CDS_LIB"standard"
BODY_TYPE"PLUMBING"
HDL_TAP"TRUE";
"B \NAC \NWC"4;
"S \NAC"
BN"9"95;
%"TAP"
"6","(-2925,1775)","2","standard","I499";
;
ROOM"RISER1"
BOM_COST"IO_SLOT"
CDS_LIB"standard"
BODY_TYPE"PLUMBING"
HDL_TAP"TRUE";
"B \NAC \NWC"4;
"S \NAC"
BN"12"99;
%"TAP"
"6","(-2925,1875)","2","standard","I500";
;
ROOM"RISER1"
BOM_COST"IO_SLOT"
CDS_LIB"standard"
BODY_TYPE"PLUMBING"
HDL_TAP"TRUE";
"B \NAC \NWC"4;
"S \NAC"
BN"11"100;
%"TAP"
"6","(-2925,1675)","2","standard","I501";
;
ROOM"RISER1"
BOM_COST"IO_SLOT"
CDS_LIB"standard"
BODY_TYPE"PLUMBING"
HDL_TAP"TRUE";
"B \NAC \NWC"4;
"S \NAC"
BN"13"98;
%"TAP"
"6","(-2925,1575)","2","standard","I502";
;
ROOM"RISER1"
CDS_LIB"standard"
BOM_COST"IO_SLOT"
BODY_TYPE"PLUMBING"
HDL_TAP"TRUE";
"B \NAC \NWC"4;
"S \NAC"
BN"14"97;
%"TAP"
"6","(-2925,1475)","2","standard","I503";
;
ROOM"RISER1"
BOM_COST"IO_SLOT"
CDS_LIB"standard"
BODY_TYPE"PLUMBING"
HDL_TAP"TRUE";
"B \NAC \NWC"4;
"S \NAC"
BN"15"96;
END.
